(kicad_pcb
	(version 20241229)
	(generator "pcbnew")
	(generator_version "9.0")
	(general
		(thickness 1.711)
		(legacy_teardrops no)
	)
	(paper "A4")
	(title_block
		(title "Antmicro Baseboard for Jetson AGX Thor")
		(date "2026-02-18")
		(rev "1.1.0")
		(company "Antmicro Ltd")
		(comment 1 "www.antmicro.com")
		(comment 9 "footprints 370-372 of 1170")
	)
	(layers
		(0 "F.Cu" signal)
		(4 "In1.Cu" signal)
		(6 "In2.Cu" signal)
		(8 "In3.Cu" signal)
		(10 "In4.Cu" jumper)
		(12 "In5.Cu" signal)
		(14 "In6.Cu" signal)
		(16 "In7.Cu" signal)
		(18 "In8.Cu" signal)
		(2 "B.Cu" signal)
		(9 "F.Adhes" user "F.Adhesive")
		(11 "B.Adhes" user "B.Adhesive")
		(13 "F.Paste" user)
		(15 "B.Paste" user)
		(5 "F.SilkS" user "F.Silkscreen")
		(7 "B.SilkS" user "B.Silkscreen")
		(1 "F.Mask" user)
		(3 "B.Mask" user)
		(17 "Dwgs.User" user "User.Drawings")
		(19 "Cmts.User" user "User.Comments")
		(21 "Eco1.User" user "User.Eco1")
		(23 "Eco2.User" user "User.Eco2")
		(25 "Edge.Cuts" user)
		(27 "Margin" user)
		(31 "F.CrtYd" user "F.Courtyard")
		(29 "B.CrtYd" user "B.Courtyard")
		(35 "F.Fab" user)
		(33 "B.Fab" user)
	)
	(footprint "antmicro-footprints:C_0805_2012Metric"
		(layer "F.Cu")
		(at 172.71 142.39 90)
		(descr "Capacitor SMD 0805")
		(tags "capacitor SMD 0805")
		(property "Reference" "C29"
			(at 1.92 0.23 90)
			(layer "F.SilkS")
			(effects
				(font
					(size 0.7 0.7)
					(thickness 0.15)
				)
				(justify left bottom)
			)
		)
		(property "Value" "C_22u_25V_0805"
			(at -2.055717 1.963152 90)
			(layer "F.Fab")
			(effects
				(font
					(size 0.7 0.7)
					(thickness 0.15)
				)
				(justify left bottom)
			)
		)
		(property "Datasheet" "https://product.samsungsem.com/mlcc/CL21A226MAYNNN.do"
			(at 0 0 90)
			(layer "F.Fab")
			(hide yes)
			(effects
				(font
					(size 1.27 1.27)
					(thickness 0.15)
				)
			)
		)
		(property "Description" "SMT Multilayer Ceramic Capacitor, 22uF, +/-20%, 25V, X5R, 0805 [2012 Metric]"
			(at 0 0 90)
			(layer "F.Fab")
			(hide yes)
			(effects
				(font
					(size 1.27 1.27)
					(thickness 0.15)
				)
			)
		)
		(property "Manufacturer" "Samsung Electro-Mechanics"
			(at 0 0 90)
			(unlocked yes)
			(layer "F.Fab")
			(hide yes)
			(effects
				(font
					(size 1 1)
					(thickness 0.15)
				)
			)
		)
		(property "MPN" "CL21A226MAYNNNE"
			(at 0 0 90)
			(unlocked yes)
			(layer "F.Fab")
			(hide yes)
			(effects
				(font
					(size 1 1)
					(thickness 0.15)
				)
			)
		)
		(property "Val" "22u"
			(at 0 0 90)
			(unlocked yes)
			(layer "F.Fab")
			(hide yes)
			(effects
				(font
					(size 1 1)
					(thickness 0.15)
				)
			)
		)
		(property "License" "Apache-2.0"
			(at 0 0 90)
			(unlocked yes)
			(layer "F.Fab")
			(hide yes)
			(effects
				(font
					(size 1 1)
					(thickness 0.15)
				)
			)
		)
		(property "Author" "Antmicro"
			(at 0 0 90)
			(unlocked yes)
			(layer "F.Fab")
			(hide yes)
			(effects
				(font
					(size 1 1)
					(thickness 0.15)
				)
			)
		)
		(property "Voltage" "25V"
			(at 0 0 90)
			(unlocked yes)
			(layer "F.Fab")
			(hide yes)
			(effects
				(font
					(size 1 1)
					(thickness 0.15)
				)
			)
		)
		(property "Dielectric" "X5R"
			(at 0 0 90)
			(unlocked yes)
			(layer "F.Fab")
			(hide yes)
			(effects
				(font
					(size 1 1)
					(thickness 0.15)
				)
			)
		)
		(property "Public" "False"
			(at 0 0 90)
			(unlocked yes)
			(layer "F.Fab")
			(hide yes)
			(effects
				(font
					(size 1 1)
					(thickness 0.15)
				)
			)
		)
		(sheetname "/DCDC/")
		(sheetfile "dcdc.kicad_sch")
		(attr smd)
		(fp_line
			(start -0.3 -0.7)
			(end 0.3 -0.7)
			(stroke
				(width 0.15)
				(type solid)
			)
			(layer "F.SilkS")
		)
		(fp_line
			(start -0.3 0.7)
			(end 0.3 0.7)
			(stroke
				(width 0.15)
				(type solid)
			)
			(layer "F.SilkS")
		)
		(fp_rect
			(start 1.95 -0.9)
			(end -1.95 0.9)
			(stroke
				(width 0.05)
				(type default)
			)
			(fill no)
			(layer "F.CrtYd")
		)
		(fp_rect
			(start -0.95 -0.675)
			(end 0.95 0.675)
			(stroke
				(width 0.15)
				(type solid)
			)
			(fill no)
			(layer "F.Fab")
		)
		(fp_text user "License: Apache-2.0"
			(at -1.9 4.947 90)
			(layer "F.Fab")
			(effects
				(font
					(size 0.7 0.7)
					(thickness 0.15)
				)
				(justify left bottom)
			)
		)
		(fp_text user "${REFERENCE}"
			(at -1.9 3.947 90)
			(layer "F.Fab")
			(effects
				(font
					(size 0.7 0.7)
					(thickness 0.15)
				)
				(justify left bottom)
			)
		)
		(fp_text user "Author: Antmicro"
			(at -1.9 5.947 90)
			(layer "F.Fab")
			(effects
				(font
					(size 0.7 0.7)
					(thickness 0.15)
				)
				(justify left bottom)
			)
		)
		(pad "1" smd roundrect
			(at -1.1 0 90)
			(size 1.2 1.3)
			(layers "F.Cu" "F.Mask" "F.Paste")
			(roundrect_rratio 0.25)
			(net 1 "GND")
			(pintype "passive")
		)
		(pad "2" smd roundrect
			(at 1.1 0 90)
			(size 1.2 1.3)
			(layers "F.Cu" "F.Mask" "F.Paste")
			(roundrect_rratio 0.25)
			(net 13 "VCC")
			(pintype "passive")
		)
	)
	(footprint "antmicro-footprints:USB-C_Receptacle_Kycon_KUSBX-SL2-CS1N24-B-TR"
		(locked yes)
		(layer "F.Cu")
		(at 236.455532 102.21 90)
		(descr "USB-C (USB TYPE-C) USB 3.2 Gen 2 (USB 3.1 Gen 2, Superspeed + (USB 3.1)) Receptacle Connector 24 Position Through Hole, Right Angle")
		(tags "CONNECTOR, USB")
		(property "Reference" "J3"
			(at 3.21 -10.685532 180)
			(layer "F.SilkS")
			(effects
				(font
					(size 0.7 0.7)
					(thickness 0.15)
				)
				(justify left bottom)
			)
		)
		(property "Value" "USB-C_Kycon_KUSBX-SL2-CS1N24-B-TR"
			(at 0 7.5 90)
			(layer "F.Fab")
			(effects
				(font
					(size 0.7 0.7)
					(thickness 0.15)
				)
				(justify right top)
			)
		)
		(property "Datasheet" "https://www.kycon.com/Pub_Eng_Draw/KUSBX-SL2-CS1N24-B-TR.pdf"
			(at 0 0 90)
			(layer "F.Fab")
			(hide yes)
			(effects
				(font
					(size 1.27 1.27)
					(thickness 0.15)
				)
			)
		)
		(property "Description" "USB-C (USB TYPE-C) USB 3.2 Gen 2 (USB 3.1 Gen 2, Superspeed + (USB 3.1)) USB PD Receptacle Connector 24 Position Surface Mount"
			(at 0 0 90)
			(layer "F.Fab")
			(hide yes)
			(effects
				(font
					(size 1.27 1.27)
					(thickness 0.15)
				)
			)
		)
		(property "MPN" "KUSBX-SL2-CS1N24-B-TR"
			(at 0 0 90)
			(unlocked yes)
			(layer "F.Fab")
			(hide yes)
			(effects
				(font
					(size 1 1)
					(thickness 0.15)
				)
			)
		)
		(property "Manufacturer" "Kycon"
			(at 0 0 90)
			(unlocked yes)
			(layer "F.Fab")
			(hide yes)
			(effects
				(font
					(size 1 1)
					(thickness 0.15)
				)
			)
		)
		(property "License" "Apache-2.0"
			(at 0 0 90)
			(unlocked yes)
			(layer "F.Fab")
			(hide yes)
			(effects
				(font
					(size 1 1)
					(thickness 0.15)
				)
			)
		)
		(property "Author" "Antmicro"
			(at 0 0 90)
			(unlocked yes)
			(layer "F.Fab")
			(hide yes)
			(effects
				(font
					(size 1 1)
					(thickness 0.15)
				)
			)
		)
		(sheetname "/Recovery USB/")
		(sheetfile "recovery_usb.kicad_sch")
		(attr smd)
		(fp_line
			(start 1 -8.8)
			(end 1 -8.8)
			(stroke
				(width 0.15)
				(type solid)
			)
			(layer "F.SilkS")
		)
		(fp_line
			(start 1 -8.8)
			(end -1 -8.8)
			(stroke
				(width 0.15)
				(type solid)
			)
			(layer "F.SilkS")
		)
		(fp_line
			(start -1 -8.8)
			(end 1 -8.8)
			(stroke
				(width 0.15)
				(type solid)
			)
			(layer "F.SilkS")
		)
		(fp_line
			(start -1 -8.8)
			(end -1 -8.8)
			(stroke
				(width 0.15)
				(type solid)
			)
			(layer "F.SilkS")
		)
		(fp_rect
			(start -4 -9.4)
			(end 4 5.65)
			(stroke
				(width 0.05)
				(type solid)
			)
			(fill no)
			(layer "F.CrtYd")
		)
		(fp_line
			(start 2.25 -8.8)
			(end -2.25 -8.8)
			(stroke
				(width 0.15)
				(type solid)
			)
			(layer "F.Fab")
		)
		(fp_line
			(start -2.25 -8.8)
			(end -2.25 5.5)
			(stroke
				(width 0.15)
				(type solid)
			)
			(layer "F.Fab")
		)
		(fp_line
			(start 2.25 5.5)
			(end 2.25 -8.8)
			(stroke
				(width 0.15)
				(type solid)
			)
			(layer "F.Fab")
		)
		(fp_line
			(start -2.25 5.5)
			(end 2.25 5.5)
			(stroke
				(width 0.15)
				(type solid)
			)
			(layer "F.Fab")
		)
		(fp_text user "${REFERENCE}"
			(at -5.47 8.5 90)
			(layer "F.Fab")
			(effects
				(font
					(size 0.7 0.7)
					(thickness 0.15)
				)
				(justify left bottom)
			)
		)
		(fp_text user "License: Apache-2.0"
			(at -5.47 10.9 90)
			(layer "F.Fab")
			(effects
				(font
					(size 0.7 0.7)
					(thickness 0.15)
				)
				(justify left bottom)
			)
		)
		(fp_text user "Author: Antmicro"
			(at -5.47 9.7 90)
			(layer "F.Fab")
			(effects
				(font
					(size 0.7 0.7)
					(thickness 0.15)
				)
				(justify left bottom)
			)
		)
		(pad "" np_thru_hole circle
			(at 0 -7.6 90)
			(size 1.1 1.1)
			(drill 1.1)
			(layers "*.Cu" "*.Mask")
		)
		(pad "" np_thru_hole circle
			(at 0 0 90)
			(size 1 1)
			(drill 1)
			(layers "*.Cu" "*.Mask")
		)
		(pad "A1" smd rect
			(at 1.1375 -6.525 180)
			(size 0.25 1.625)
			(layers "F.Cu" "F.Mask" "F.Paste")
			(net 1 "GND")
			(pinfunction "GND")
			(pintype "power_in")
		)
		(pad "A2" smd rect
			(at 1.1375 -6.025 180)
			(size 0.25 1.625)
			(layers "F.Cu" "F.Mask" "F.Paste")
			(net 215 "/Recovery USB/USBC2_CONN_TX1_N")
			(pinfunction "TX_{1}+")
			(pintype "bidirectional")
		)
		(pad "A3" smd rect
			(at 1.1375 -5.525 180)
			(size 0.25 1.625)
			(layers "F.Cu" "F.Mask" "F.Paste")
			(net 245 "/Recovery USB/USBC2_CONN_TX1_P")
			(pinfunction "TX_{1}-")
			(pintype "bidirectional")
		)
		(pad "A4" smd rect
			(at 1.1375 -5.025 180)
			(size 0.25 1.625)
			(layers "F.Cu" "F.Mask" "F.Paste")
			(net 287 "/Recovery USB/USBC2_VBUS")
			(pinfunction "VBUS")
			(pintype "power_in")
		)
		(pad "A5" smd rect
			(at 1.1375 -4.525 180)
			(size 0.25 1.625)
			(layers "F.Cu" "F.Mask" "F.Paste")
			(net 806 "/Recovery USB/USBC2_CC1")
			(pinfunction "CC_{1}")
			(pintype "bidirectional")
		)
		(pad "A6" smd rect
			(at 1.1375 -4.025 180)
			(size 0.25 1.625)
			(layers "F.Cu" "F.Mask" "F.Paste")
			(net 766 "/Recovery USB/USB0.D+")
			(pinfunction "D_{A}+")
			(pintype "bidirectional")
		)
		(pad "A7" smd rect
			(at 1.1375 -3.525 180)
			(size 0.25 1.625)
			(layers "F.Cu" "F.Mask" "F.Paste")
			(net 698 "/Recovery USB/USB0.D-")
			(pinfunction "D_{A}-")
			(pintype "bidirectional")
		)
		(pad "A8" smd rect
			(at 1.1375 -3.025 180)
			(size 0.25 1.625)
			(layers "F.Cu" "F.Mask" "F.Paste")
			(net 803 "unconnected-(J3-SBU_{1}-PadA8)")
			(pinfunction "SBU_{1}")
			(pintype "bidirectional+no_connect")
		)
		(pad "A9" smd rect
			(at 1.1375 -2.525 180)
			(size 0.25 1.625)
			(layers "F.Cu" "F.Mask" "F.Paste")
			(net 287 "/Recovery USB/USBC2_VBUS")
			(pinfunction "VBUS")
			(pintype "passive")
		)
		(pad "A10" smd rect
			(at 1.1375 -2.025 180)
			(size 0.25 1.625)
			(layers "F.Cu" "F.Mask" "F.Paste")
			(net 804 "/Recovery USB/USBC2_RX2_P")
			(pinfunction "RX_{2}-")
			(pintype "bidirectional")
		)
		(pad "A11" smd rect
			(at 1.1375 -1.525 180)
			(size 0.25 1.625)
			(layers "F.Cu" "F.Mask" "F.Paste")
			(net 807 "/Recovery USB/USBC2_RX2_N")
			(pinfunction "RX_{2}+")
			(pintype "bidirectional")
		)
		(pad "A12" smd rect
			(at 1.1375 -1.025 180)
			(size 0.25 1.625)
			(layers "F.Cu" "F.Mask" "F.Paste")
			(net 1 "GND")
			(pinfunction "GND")
			(pintype "passive")
		)
		(pad "B1" smd rect
			(at -1.1375 -1.025 180)
			(size 0.25 1.625)
			(layers "F.Cu" "F.Mask" "F.Paste")
			(net 1 "GND")
			(pinfunction "GND")
			(pintype "passive")
		)
		(pad "B2" smd rect
			(at -1.1375 -1.525 180)
			(size 0.25 1.625)
			(layers "F.Cu" "F.Mask" "F.Paste")
			(net 270 "/Recovery USB/USBC2_CONN_TX2_P")
			(pinfunction "TX_{2}+")
			(pintype "bidirectional")
		)
		(pad "B3" smd rect
			(at -1.1375 -2.025 180)
			(size 0.25 1.625)
			(layers "F.Cu" "F.Mask" "F.Paste")
			(net 241 "/Recovery USB/USBC2_CONN_TX2_N")
			(pinfunction "TX_{2}-")
			(pintype "bidirectional")
		)
		(pad "B4" smd rect
			(at -1.1375 -2.525 180)
			(size 0.25 1.625)
			(layers "F.Cu" "F.Mask" "F.Paste")
			(net 287 "/Recovery USB/USBC2_VBUS")
			(pinfunction "VBUS")
			(pintype "passive")
		)
		(pad "B5" smd rect
			(at -1.1375 -3.025 180)
			(size 0.25 1.625)
			(layers "F.Cu" "F.Mask" "F.Paste")
			(net 801 "/Recovery USB/USBC2_CC2")
			(pinfunction "CC_{2}")
			(pintype "bidirectional")
		)
		(pad "B6" smd rect
			(at -1.1375 -3.525 180)
			(size 0.25 1.625)
			(layers "F.Cu" "F.Mask" "F.Paste")
			(net 766 "/Recovery USB/USB0.D+")
			(pinfunction "D_{B}+")
			(pintype "bidirectional")
		)
		(pad "B7" smd rect
			(at -1.1375 -4.025 180)
			(size 0.25 1.625)
			(layers "F.Cu" "F.Mask" "F.Paste")
			(net 698 "/Recovery USB/USB0.D-")
			(pinfunction "D_{B}-")
			(pintype "bidirectional")
		)
		(pad "B8" smd rect
			(at -1.1375 -4.525 180)
			(size 0.25 1.625)
			(layers "F.Cu" "F.Mask" "F.Paste")
			(net 805 "unconnected-(J3-SBU_{2}-PadB8)")
			(pinfunction "SBU_{2}")
			(pintype "bidirectional+no_connect")
		)
		(pad "B9" smd rect
			(at -1.1375 -5.025 180)
			(size 0.25 1.625)
			(layers "F.Cu" "F.Mask" "F.Paste")
			(net 287 "/Recovery USB/USBC2_VBUS")
			(pinfunction "VBUS")
			(pintype "passive")
		)
		(pad "B10" smd rect
			(at -1.1375 -5.525 180)
			(size 0.25 1.625)
			(layers "F.Cu" "F.Mask" "F.Paste")
			(net 800 "/Recovery USB/USBC2_RX1_N")
			(pinfunction "RX_{1}-")
			(pintype "bidirectional")
		)
		(pad "B11" smd rect
			(at -1.1375 -6.025 180)
			(size 0.25 1.625)
			(layers "F.Cu" "F.Mask" "F.Paste")
			(net 802 "/Recovery USB/USBC2_RX1_P")
			(pinfunction "RX_{1}+")
			(pintype "bidirectional")
		)
		(pad "B12" smd rect
			(at -1.1375 -6.525 180)
			(size 0.25 1.625)
			(layers "F.Cu" "F.Mask" "F.Paste")
			(net 1 "GND")
			(pinfunction "GND")
			(pintype "passive")
		)
		(pad "SH" thru_hole oval
			(at -3 -7.849 90)
			(size 1 2.05)
			(drill oval 0.6 1.65)
			(layers "*.Cu" "*.Mask")
			(remove_unused_layers no)
			(net 1 "GND")
			(pinfunction "SH")
			(pintype "passive")
		)
		(pad "SH" thru_hole oval
			(at -3 0.25 90)
			(size 1 2.05)
			(drill oval 0.6 1.65)
			(layers "*.Cu" "*.Mask")
			(remove_unused_layers no)
			(net 1 "GND")
			(pinfunction "SH")
			(pintype "passive")
		)
		(pad "SH" thru_hole oval
			(at 3 -7.849 90)
			(size 1 2.05)
			(drill oval 0.6 1.65)
			(layers "*.Cu" "*.Mask")
			(remove_unused_layers no)
			(net 1 "GND")
			(pinfunction "SH")
			(pintype "passive")
		)
		(pad "SH" thru_hole oval
			(at 3 0.25 90)
			(size 1 2.05)
			(drill oval 0.6 1.65)
			(layers "*.Cu" "*.Mask")
			(remove_unused_layers no)
			(net 1 "GND")
			(pinfunction "SH")
			(pintype "passive")
		)
	)
	(footprint "antmicro-footprints:Spacer_Drill4.45mm_H4mm_9774040960R"
		(locked yes)
		(layer "F.Cu")
		(at 155.930532 57.71 90)
		(property "Reference" "H7"
			(at 1.86 -3.45 90)
			(layer "F.SilkS")
			(effects
				(font
					(size 0.7 0.7)
					(thickness 0.15)
				)
				(justify left bottom)
			)
		)
		(property "Value" "Spacer_Drill4.45mm_H4mm_9774040960R"
			(at -3.95 5.05 90)
			(layer "F.Fab")
			(effects
				(font
					(size 0.7 0.7)
					(thickness 0.15)
				)
				(justify left bottom)
			)
		)
		(property "Datasheet" "https://www.we-online.com/components/products/datasheet/9774040960R.pdf"
			(at 0 0 90)
			(layer "F.Fab")
			(effects
				(font
					(size 0.7 0.7)
					(thickness 0.15)
				)
				(justify left bottom)
			)
		)
		(property "Description" "Spacer, SMT, Non Stop, Steel, Swage Round, 6 mm x 4 mm, 3.3 mm Internal, WA-SMST Series"
			(at 0 0 90)
			(layer "F.Fab")
			(effects
				(font
					(size 0.7 0.7)
					(thickness 0.15)
				)
				(justify left bottom)
			)
		)
		(property "Manufacturer" "Würth Elektronik"
			(at 0 0 90)
			(unlocked yes)
			(layer "F.Fab")
			(hide yes)
			(effects
				(font
					(size 1 1)
					(thickness 0.15)
				)
			)
		)
		(property "MPN" "9774040960R"
			(at 0 0 90)
			(unlocked yes)
			(layer "F.Fab")
			(hide yes)
			(effects
				(font
					(size 1 1)
					(thickness 0.15)
				)
			)
		)
		(property "Author" "Antmicro"
			(at 0 0 90)
			(unlocked yes)
			(layer "F.Fab")
			(hide yes)
			(effects
				(font
					(size 1 1)
					(thickness 0.15)
				)
			)
		)
		(property "License" "Apache-2.0"
			(at 0 0 90)
			(unlocked yes)
			(layer "F.Fab")
			(hide yes)
			(effects
				(font
					(size 1 1)
					(thickness 0.15)
				)
			)
		)
		(sheetname "/SoM_Power/")
		(sheetfile "som_power.kicad_sch")
		(attr smd)
		(fp_rect
			(start -3.95 -3.95)
			(end 3.95 3.95)
			(stroke
				(width 0.05)
				(type solid)
			)
			(fill no)
			(layer "F.CrtYd")
		)
		(fp_circle
			(center 0 0)
			(end 3.25 0)
			(stroke
				(width 0.05)
				(type solid)
			)
			(fill no)
			(layer "F.CrtYd")
		)
		(fp_circle
			(center 0 0)
			(end 2.564 0)
			(stroke
				(width 0.15)
				(type solid)
			)
			(fill no)
			(layer "F.Fab")
		)
		(fp_text user "Author: Antmicro"
			(at -3.95 8.65 90)
			(layer "F.Fab")
			(effects
				(font
					(size 0.7 0.7)
					(thickness 0.15)
				)
				(justify left bottom)
			)
		)
		(fp_text user "${REFERENCE}"
			(at -3.95 7.45 90)
			(layer "F.Fab")
			(effects
				(font
					(size 0.7 0.7)
					(thickness 0.15)
				)
				(justify left bottom)
			)
		)
		(fp_text user "License: Apache-2.0"
			(at -3.95 6.25 90)
			(layer "F.Fab")
			(effects
				(font
					(size 0.7 0.7)
					(thickness 0.15)
				)
				(justify left bottom)
			)
		)
		(pad "" smd custom
			(at -2.55 -0.55 212.5)
			(size 0.1 0.1)
			(layers "F.Paste")
			(options
				(clearance outline)
				(anchor circle)
			)
			(primitives
				(gr_arc
					(start 0 0)
					(mid 0.704278 1.28373)
					(end 0.608513 2.744826)
					(width 0.7)
				)
			)
		)
		(pad "" smd custom
			(at -0.55 2.55 302.5)
			(size 0.1 0.1)
			(layers "F.Paste")
			(options
				(clearance outline)
				(anchor circle)
			)
			(primitives
				(gr_arc
					(start 0 0)
					(mid 0.704278 1.28373)
					(end 0.608513 2.744826)
					(width 0.7)
				)
			)
		)
		(pad "" smd custom
			(at 0.55 -2.55 122.5)
			(size 0.1 0.1)
			(layers "F.Paste")
			(options
				(clearance outline)
				(anchor circle)
			)
			(primitives
				(gr_arc
					(start 0 0)
					(mid 0.704278 1.28373)
					(end 0.608513 2.744826)
					(width 0.7)
				)
			)
		)
		(pad "" smd custom
			(at 2.55 0.55 32.5)
			(size 0.1 0.1)
			(layers "F.Paste")
			(options
				(clearance outline)
				(anchor circle)
			)
			(primitives
				(gr_arc
					(start 0 0)
					(mid 0.704278 1.28373)
					(end 0.608513 2.744826)
					(width 0.7)
				)
			)
		)
		(pad "1" thru_hole circle
			(at 0 0 90)
			(size 7.4 7.4)
			(drill 4.45)
			(layers "*.Cu" "*.Mask")
			(remove_unused_layers no)
			(net 1 "GND")
			(pintype "passive")
		)
	)
)
